# BASEBOARD_FAB2 (Tioga Pass) — schematic netlist excerpt (pin names and nets, part order shuffled) for the footprints in the layout excerpt that follows; sources: Cadence DE-HDL packaged netlist, KiCad conversion of Wiwynn_Tioga_Pass_MB.brd

R25W178  RES  1.00K 1% CHIP  pkg 0402  page 254 : A = P3V3_STBY ; B = BMC_PWR_DEBUG_BUF_N
R2L9  RES  4.02K 1% CHIP  pkg 0402  page 235 : A = VR_PVNN_PCH_XADDR1 ; B = GND
C5G93  CAP_A  22.0UF 4V 20% X6S  pkg 0603V  page 243 : A = PVDDQ_GHJ ; B = GND

(kicad_pcb
	(version 20260206)
	(generator "pcbnew")
	(generator_version "10.0")
	(general
		(thickness 1.6)
		(legacy_teardrops no)
	)
	(paper "A4")
	(title_block
		(title "Wiwynn_Tioga_Pass_MB.brd")
		(comment 1 "Tioga Pass / footprints 2361-2363 of 4770")
	)
	(layers
		(0 "F.Cu" signal "TOP")
		(4 "In1.Cu" signal "L2GND")
		(6 "In2.Cu" signal "L3")
		(8 "In3.Cu" signal "L4GND")
		(10 "In4.Cu" signal "L5")
		(12 "In5.Cu" signal "L6GND")
		(14 "In6.Cu" signal "L7VCC")
		(16 "In7.Cu" signal "L8VCC")
		(18 "In8.Cu" signal "L9GND")
		(20 "In9.Cu" signal "L10")
		(22 "In10.Cu" signal "L11GND")
		(24 "In11.Cu" signal "L12")
		(26 "In12.Cu" signal "L13GND")
		(2 "B.Cu" signal "BOTTOM")
		(9 "F.Adhes" user "F.Adhesive")
		(11 "B.Adhes" user "B.Adhesive")
		(13 "F.Paste" user "Package Geometry/Pastemask Top")
		(15 "B.Paste" user "Package Geometry/Pastemask Bottom")
		(5 "F.SilkS" user "Ref Des/Silkscreen Top")
		(7 "B.SilkS" user "Ref Des/Silkscreen Bottom")
		(1 "F.Mask" user "Board Geometry/Soldermask Top")
		(3 "B.Mask" user "Board Geometry/Soldermask Bottom")
		(17 "Dwgs.User" user "User.Drawings")
		(19 "Cmts.User" user "User.Comments")
		(21 "Eco1.User" user "User.Eco1")
		(23 "Eco2.User" user "User.Eco2")
		(25 "Edge.Cuts" user "Board Geometry/Outline")
		(27 "Margin" user)
		(31 "F.CrtYd" user "Package Geometry/Place Bound Top")
		(29 "B.CrtYd" user "Package Geometry/Place Bound Bottom")
		(35 "F.Fab" user "Ref Des/Assembly Top")
		(33 "B.Fab" user "Ref Des/Assembly Bottom")
	)
	(footprint ""
		(layer "B.Cu")
		(at 443.1538 -142.0368 -90)
		(property "Reference" "R25W178"
			(at 0.8382 -0.67818 270)
			(unlocked yes)
			(layer "B.SilkS")
			(effects
				(font
					(size 0.4064 0.254)
					(thickness 0.1524)
				)
				(justify left mirror)
			)
		)
		(property "Value" ""
			(at 0 0 90)
			(layer "B.Fab")
			(effects
				(font
					(size 1.27 1.27)
				)
				(justify mirror)
			)
		)
		(duplicate_pad_numbers_are_jumpers no)
		(fp_poly
			(pts
				(xy 0.2794 -0.1016) (xy -0.2794 -0.1016) (xy -0.2794 0.9906) (xy 0.2794 0.9906)
			)
			(stroke
				(width 0)
				(type default)
			)
			(fill no)
			(layer "B.CrtYd")
		)
		(fp_line
			(start -0.2794 0.9906)
			(end -0.2794 -0.1016)
			(stroke
				(width 0.1)
				(type default)
			)
			(layer "B.Fab")
		)
		(fp_line
			(start 0.2794 0.9906)
			(end -0.2794 0.9906)
			(stroke
				(width 0.1)
				(type default)
			)
			(layer "B.Fab")
		)
		(fp_line
			(start -0.2794 -0.1016)
			(end 0.2794 -0.1016)
			(stroke
				(width 0.1)
				(type default)
			)
			(layer "B.Fab")
		)
		(fp_line
			(start 0.2794 -0.1016)
			(end 0.2794 0.9906)
			(stroke
				(width 0.1)
				(type default)
			)
			(layer "B.Fab")
		)
		(pad "1" smd rect
			(at 0 0 90)
			(size 0.508 0.508)
			(layers "B.Cu" "B.Mask" "B.Paste")
			(net "P3V3_STBY")
		)
		(pad "2" smd rect
			(at 0 0.889 90)
			(size 0.508 0.508)
			(layers "B.Cu" "B.Mask" "B.Paste")
			(net "BMC_PWR_DEBUG_BUF_N")
		)
		(zone
			(layer "B.Cu")
			(hatch none 0.5)
			(connect_pads
				(clearance 0)
			)
			(min_thickness 0.25)
			(keepout
				(tracks not_allowed)
				(vias allowed)
				(pads allowed)
				(copperpour not_allowed)
				(footprints allowed)
			)
			(placement
				(enabled no)
				(sheetname "")
			)
			(fill
				(thermal_gap 0.5)
				(thermal_bridge_width 0.5)
				(island_removal_mode 0)
			)
			(polygon
				(pts
					(xy 442.5188 -141.7828) (xy 442.5188 -142.2908) (xy 442.8998 -142.2908) (xy 442.8998 -141.7828)
				)
			)
		)
		(zone
			(layer "B.Cu")
			(hatch none 0.5)
			(connect_pads
				(clearance 0)
			)
			(min_thickness 0.25)
			(keepout
				(tracks allowed)
				(vias not_allowed)
				(pads allowed)
				(copperpour not_allowed)
				(footprints allowed)
			)
			(placement
				(enabled no)
				(sheetname "")
			)
			(fill
				(thermal_gap 0.5)
				(thermal_bridge_width 0.5)
				(island_removal_mode 0)
			)
			(polygon
				(pts
					(xy 442.8998 -141.7828) (xy 442.8998 -142.2908) (xy 442.5188 -142.2908) (xy 442.5188 -141.7828)
				)
			)
		)
	)
	(footprint ""
		(layer "B.Cu")
		(at 393.362688 -153.552144 90)
		(property "Reference" "R2L9"
			(at 0 0 90)
			(layer "B.SilkS")
			(hide yes)
			(effects
				(font
					(size 1.27 1.27)
				)
				(justify mirror)
			)
		)
		(property "Value" ""
			(at 0 0 90)
			(layer "B.Fab")
			(effects
				(font
					(size 1.27 1.27)
				)
				(justify mirror)
			)
		)
		(duplicate_pad_numbers_are_jumpers no)
		(fp_poly
			(pts
				(xy 0.2794 -0.1016) (xy -0.2794 -0.1016) (xy -0.2794 0.9906) (xy 0.2794 0.9906)
			)
			(stroke
				(width 0)
				(type default)
			)
			(fill no)
			(layer "B.CrtYd")
		)
		(fp_line
			(start 0.2794 -0.1016)
			(end 0.2794 0.9906)
			(stroke
				(width 0.1)
				(type default)
			)
			(layer "B.Fab")
		)
		(fp_line
			(start -0.2794 -0.1016)
			(end 0.2794 -0.1016)
			(stroke
				(width 0.1)
				(type default)
			)
			(layer "B.Fab")
		)
		(fp_line
			(start 0.2794 0.9906)
			(end -0.2794 0.9906)
			(stroke
				(width 0.1)
				(type default)
			)
			(layer "B.Fab")
		)
		(fp_line
			(start -0.2794 0.9906)
			(end -0.2794 -0.1016)
			(stroke
				(width 0.1)
				(type default)
			)
			(layer "B.Fab")
		)
		(pad "1" smd rect
			(at 0 0 270)
			(size 0.508 0.508)
			(layers "B.Cu" "B.Mask" "B.Paste")
			(net "VR_PVNN_PCH_XADDR1")
		)
		(pad "2" smd rect
			(at 0 0.889 270)
			(size 0.508 0.508)
			(layers "B.Cu" "B.Mask" "B.Paste")
			(net "GND")
		)
		(zone
			(layer "B.Cu")
			(hatch none 0.5)
			(connect_pads
				(clearance 0)
			)
			(min_thickness 0.25)
			(keepout
				(tracks allowed)
				(vias not_allowed)
				(pads allowed)
				(copperpour not_allowed)
				(footprints allowed)
			)
			(placement
				(enabled no)
				(sheetname "")
			)
			(fill
				(thermal_gap 0.5)
				(thermal_bridge_width 0.5)
				(island_removal_mode 0)
			)
			(polygon
				(pts
					(xy 393.616688 -153.806144) (xy 393.616688 -153.298144) (xy 393.997688 -153.298144) (xy 393.997688 -153.806144)
				)
			)
		)
		(zone
			(layer "B.Cu")
			(hatch none 0.5)
			(connect_pads
				(clearance 0)
			)
			(min_thickness 0.25)
			(keepout
				(tracks not_allowed)
				(vias allowed)
				(pads allowed)
				(copperpour not_allowed)
				(footprints allowed)
			)
			(placement
				(enabled no)
				(sheetname "")
			)
			(fill
				(thermal_gap 0.5)
				(thermal_bridge_width 0.5)
				(island_removal_mode 0)
			)
			(polygon
				(pts
					(xy 393.997688 -153.806144) (xy 393.997688 -153.298144) (xy 393.616688 -153.298144) (xy 393.616688 -153.806144)
				)
			)
		)
	)
	(footprint ""
		(layer "B.Cu")
		(at 101.3968 -12.954 90)
		(property "Reference" "C5G93"
			(at -1.14681 0.76708 180)
			(unlocked yes)
			(layer "B.SilkS")
			(effects
				(font
					(size 0.7874 0.5842)
					(thickness 0.1524)
				)
				(justify mirror)
			)
		)
		(property "Value" ""
			(at 0 0 90)
			(layer "B.Fab")
			(effects
				(font
					(size 1.27 1.27)
				)
				(justify mirror)
			)
		)
		(duplicate_pad_numbers_are_jumpers no)
		(fp_rect
			(start -0.4953 -0.2032)
			(end 0.4953 1.6002)
			(stroke
				(width 0)
				(type default)
			)
			(fill no)
			(layer "B.CrtYd")
		)
		(fp_line
			(start 0.4953 -0.2032)
			(end -0.4953 -0.2032)
			(stroke
				(width 0.1)
				(type default)
			)
			(layer "B.Fab")
		)
		(fp_line
			(start -0.4953 -0.2032)
			(end -0.4953 1.6002)
			(stroke
				(width 0.1)
				(type default)
			)
			(layer "B.Fab")
		)
		(fp_line
			(start 0.4953 1.6002)
			(end 0.4953 -0.2032)
			(stroke
				(width 0.1)
				(type default)
			)
			(layer "B.Fab")
		)
		(fp_line
			(start -0.4953 1.6002)
			(end 0.4953 1.6002)
			(stroke
				(width 0.1)
				(type default)
			)
			(layer "B.Fab")
		)
		(pad "1" smd rect
			(at 0 0 270)
			(size 0.762 0.889)
			(layers "B.Cu" "B.Mask" "B.Paste")
			(net "PVDDQ_GHJ")
		)
		(pad "2" smd rect
			(at 0 1.397 270)
			(size 0.762 0.889)
			(layers "B.Cu" "B.Mask" "B.Paste")
			(net "GND")
		)
		(zone
			(layer "B.Cu")
			(hatch none 0.5)
			(connect_pads
				(clearance 0)
			)
			(min_thickness 0.25)
			(keepout
				(tracks not_allowed)
				(vias allowed)
				(pads allowed)
				(copperpour not_allowed)
				(footprints allowed)
			)
			(placement
				(enabled no)
				(sheetname "")
			)
			(fill
				(thermal_gap 0.5)
				(thermal_bridge_width 0.5)
				(island_removal_mode 0)
			)
			(polygon
				(pts
					(xy 101.8413 -12.573) (xy 102.3493 -12.573) (xy 102.3493 -13.335) (xy 101.8413 -13.335)
				)
			)
		)
	)
)
